(kicad_pcb
	(version 20260206)
	(generator "pcbnew")
	(generator_version "10.0")
	(general
		(thickness 1.6)
		(legacy_teardrops no)
	)
	(paper "A4")
	(title_block
		(title "01162023_DA0F0TEBIF0_F0T_Expander_BD_F_brd_V02_OCP.brd")
		(comment 1 "Grand Teton / footprints 7614-7621 of 9728")
	)
	(layers
		(0 "F.Cu" signal "TOP")
		(4 "In1.Cu" signal "GND")
		(6 "In2.Cu" signal "VCC")
		(8 "In3.Cu" signal "VCC1")
		(10 "In4.Cu" signal "GND1")
		(12 "In5.Cu" signal "IN1")
		(14 "In6.Cu" signal "GND2")
		(16 "In7.Cu" signal "IN2")
		(18 "In8.Cu" signal "GND3")
		(20 "In9.Cu" signal "IN3")
		(22 "In10.Cu" signal "GND4")
		(24 "In11.Cu" signal "IN4")
		(26 "In12.Cu" signal "GND5")
		(28 "In13.Cu" signal "IN5")
		(30 "In14.Cu" signal "GND6")
		(32 "In15.Cu" signal "IN6")
		(34 "In16.Cu" signal "GND7")
		(2 "B.Cu" signal "BOTTOM")
		(9 "F.Adhes" user "F.Adhesive")
		(11 "B.Adhes" user "B.Adhesive")
		(13 "F.Paste" user "Package Geometry/Pastemask Top")
		(15 "B.Paste" user "Package Geometry/Pastemask Bottom")
		(5 "F.SilkS" user "Ref Des/Silkscreen Top")
		(7 "B.SilkS" user "Ref Des/Silkscreen Bottom")
		(1 "F.Mask" user "Board Geometry/Soldermask Top")
		(3 "B.Mask" user "Board Geometry/Soldermask Bottom")
		(17 "Dwgs.User" user "User.Drawings")
		(19 "Cmts.User" user "User.Comments")
		(21 "Eco1.User" user "User.Eco1")
		(23 "Eco2.User" user "User.Eco2")
		(25 "Edge.Cuts" user "Board Geometry/Outline")
		(27 "Margin" user)
		(31 "F.CrtYd" user "Package Geometry/Place Bound Top")
		(29 "B.CrtYd" user "Package Geometry/Place Bound Bottom")
		(35 "F.Fab" user "Ref Des/Assembly Top")
		(33 "B.Fab" user "Ref Des/Assembly Bottom")
	)
	(footprint ""
		(layer "B.Cu")
		(at 135.833866 -180.012594 180)
		(property "Reference" "C2659"
			(at 0 0 0)
			(layer "B.SilkS")
			(hide yes)
			(effects
				(font
					(size 1.27 1.27)
				)
				(justify mirror)
			)
		)
		(property "Value" ""
			(at 0 0 0)
			(layer "B.Fab")
			(effects
				(font
					(size 1.27 1.27)
				)
				(justify mirror)
			)
		)
		(duplicate_pad_numbers_are_jumpers no)
		(fp_line
			(start 0.7874 0.4064)
			(end 0.7874 -0.4064)
			(stroke
				(width 0.1524)
				(type default)
			)
			(layer "B.SilkS")
		)
		(fp_line
			(start 0.7874 -0.4064)
			(end -0.7874 -0.4064)
			(stroke
				(width 0.1524)
				(type default)
			)
			(layer "B.SilkS")
		)
		(fp_line
			(start -0.7874 0.4064)
			(end 0.7874 0.4064)
			(stroke
				(width 0.1524)
				(type default)
			)
			(layer "B.SilkS")
		)
		(fp_line
			(start -0.7874 -0.4064)
			(end -0.7874 0.4064)
			(stroke
				(width 0.1524)
				(type default)
			)
			(layer "B.SilkS")
		)
		(fp_line
			(start 0.67945 0.3048)
			(end 0.67945 -0.305054)
			(stroke
				(width 0.1)
				(type default)
			)
			(layer "B.Fab")
		)
		(fp_line
			(start 0.67945 -0.305054)
			(end 0.12065 -0.305054)
			(stroke
				(width 0.1)
				(type default)
			)
			(layer "B.Fab")
		)
		(fp_line
			(start 0.12065 0.3048)
			(end 0.67945 0.3048)
			(stroke
				(width 0.1)
				(type default)
			)
			(layer "B.Fab")
		)
		(fp_line
			(start 0.12065 0.2794)
			(end 0.12065 0.3048)
			(stroke
				(width 0.1)
				(type default)
			)
			(layer "B.Fab")
		)
		(fp_line
			(start 0.12065 -0.2794)
			(end -0.12065 -0.2794)
			(stroke
				(width 0.1)
				(type default)
			)
			(layer "B.Fab")
		)
		(fp_line
			(start 0.12065 -0.305054)
			(end 0.12065 -0.2794)
			(stroke
				(width 0.1)
				(type default)
			)
			(layer "B.Fab")
		)
		(fp_line
			(start -0.120396 0.3048)
			(end -0.120396 0.2794)
			(stroke
				(width 0.1)
				(type default)
			)
			(layer "B.Fab")
		)
		(fp_line
			(start -0.120396 0.2794)
			(end 0.12065 0.2794)
			(stroke
				(width 0.1)
				(type default)
			)
			(layer "B.Fab")
		)
		(fp_line
			(start -0.12065 -0.2794)
			(end -0.12065 -0.3048)
			(stroke
				(width 0.1)
				(type default)
			)
			(layer "B.Fab")
		)
		(fp_line
			(start -0.12065 -0.3048)
			(end -0.67945 -0.3048)
			(stroke
				(width 0.1)
				(type default)
			)
			(layer "B.Fab")
		)
		(fp_line
			(start -0.67945 0.3048)
			(end -0.120396 0.3048)
			(stroke
				(width 0.1)
				(type default)
			)
			(layer "B.Fab")
		)
		(fp_line
			(start -0.67945 -0.3048)
			(end -0.67945 0.3048)
			(stroke
				(width 0.1)
				(type default)
			)
			(layer "B.Fab")
		)
		(pad "1" smd circle
			(at 0.40005 0)
			(size 0 0)
			(layers "B.Cu" "B.Mask" "B.Paste")
			(net "P3V3_DB2000QL_VDD")
		)
		(pad "2" smd circle
			(at -0.40005 0)
			(size 0 0)
			(layers "B.Cu" "B.Mask" "B.Paste")
			(net "GND")
		)
	)
	(footprint ""
		(layer "B.Cu")
		(at 295.649904 -290.199826 90)
		(property "Reference" "C1748"
			(at 0 0 90)
			(layer "B.SilkS")
			(hide yes)
			(effects
				(font
					(size 1.27 1.27)
				)
				(justify mirror)
			)
		)
		(property "Value" ""
			(at 0 0 90)
			(layer "B.Fab")
			(effects
				(font
					(size 1.27 1.27)
				)
				(justify mirror)
			)
		)
		(duplicate_pad_numbers_are_jumpers no)
		(fp_line
			(start 0.299974 -0.150114)
			(end -0.299974 -0.150114)
			(stroke
				(width 0.1)
				(type default)
			)
			(layer "B.Fab")
		)
		(fp_line
			(start -0.299974 -0.150114)
			(end -0.299974 0.150114)
			(stroke
				(width 0.1)
				(type default)
			)
			(layer "B.Fab")
		)
		(fp_line
			(start 0.299974 0.150114)
			(end 0.299974 -0.150114)
			(stroke
				(width 0.1)
				(type default)
			)
			(layer "B.Fab")
		)
		(fp_line
			(start -0.299974 0.150114)
			(end 0.299974 0.150114)
			(stroke
				(width 0.1)
				(type default)
			)
			(layer "B.Fab")
		)
		(pad "1" smd rect
			(at 0.2667 0 270)
			(size 0.3048 0.381)
			(layers "B.Cu" "B.Mask" "B.Paste")
			(net "P0V8_SERDES_VDDA_PEX2")
		)
		(pad "2" smd rect
			(at -0.2667 0 270)
			(size 0.3048 0.381)
			(layers "B.Cu" "B.Mask" "B.Paste")
			(net "GND")
		)
	)
	(footprint ""
		(layer "B.Cu")
		(at 11.143234 -380.959106 90)
		(property "Reference" "C4469"
			(at 0 0 90)
			(layer "B.SilkS")
			(hide yes)
			(effects
				(font
					(size 1.27 1.27)
				)
				(justify mirror)
			)
		)
		(property "Value" ""
			(at 0 0 90)
			(layer "B.Fab")
			(effects
				(font
					(size 1.27 1.27)
				)
				(justify mirror)
			)
		)
		(duplicate_pad_numbers_are_jumpers no)
		(fp_line
			(start 0.7874 -0.4064)
			(end -0.7874 -0.4064)
			(stroke
				(width 0.1524)
				(type default)
			)
			(layer "B.SilkS")
		)
		(fp_line
			(start -0.7874 -0.4064)
			(end -0.7874 0.4064)
			(stroke
				(width 0.1524)
				(type default)
			)
			(layer "B.SilkS")
		)
		(fp_line
			(start 0.7874 0.4064)
			(end 0.7874 -0.4064)
			(stroke
				(width 0.1524)
				(type default)
			)
			(layer "B.SilkS")
		)
		(fp_line
			(start -0.7874 0.4064)
			(end 0.7874 0.4064)
			(stroke
				(width 0.1524)
				(type default)
			)
			(layer "B.SilkS")
		)
		(fp_line
			(start 0.67945 -0.305054)
			(end 0.12065 -0.305054)
			(stroke
				(width 0.1)
				(type default)
			)
			(layer "B.Fab")
		)
		(fp_line
			(start 0.12065 -0.305054)
			(end 0.12065 -0.2794)
			(stroke
				(width 0.1)
				(type default)
			)
			(layer "B.Fab")
		)
		(fp_line
			(start -0.12065 -0.3048)
			(end -0.67945 -0.3048)
			(stroke
				(width 0.1)
				(type default)
			)
			(layer "B.Fab")
		)
		(fp_line
			(start -0.67945 -0.3048)
			(end -0.67945 0.3048)
			(stroke
				(width 0.1)
				(type default)
			)
			(layer "B.Fab")
		)
		(fp_line
			(start 0.12065 -0.2794)
			(end -0.12065 -0.2794)
			(stroke
				(width 0.1)
				(type default)
			)
			(layer "B.Fab")
		)
		(fp_line
			(start -0.12065 -0.2794)
			(end -0.12065 -0.3048)
			(stroke
				(width 0.1)
				(type default)
			)
			(layer "B.Fab")
		)
		(fp_line
			(start 0.12065 0.2794)
			(end 0.12065 0.3048)
			(stroke
				(width 0.1)
				(type default)
			)
			(layer "B.Fab")
		)
		(fp_line
			(start -0.120396 0.2794)
			(end 0.12065 0.2794)
			(stroke
				(width 0.1)
				(type default)
			)
			(layer "B.Fab")
		)
		(fp_line
			(start 0.67945 0.3048)
			(end 0.67945 -0.305054)
			(stroke
				(width 0.1)
				(type default)
			)
			(layer "B.Fab")
		)
		(fp_line
			(start 0.12065 0.3048)
			(end 0.67945 0.3048)
			(stroke
				(width 0.1)
				(type default)
			)
			(layer "B.Fab")
		)
		(fp_line
			(start -0.120396 0.3048)
			(end -0.120396 0.2794)
			(stroke
				(width 0.1)
				(type default)
			)
			(layer "B.Fab")
		)
		(fp_line
			(start -0.67945 0.3048)
			(end -0.120396 0.3048)
			(stroke
				(width 0.1)
				(type default)
			)
			(layer "B.Fab")
		)
		(pad "1" smd circle
			(at 0.40005 0 270)
			(size 0 0)
			(layers "B.Cu" "B.Mask" "B.Paste")
			(net "P1V2_USB_8042")
		)
		(pad "2" smd circle
			(at -0.40005 0 270)
			(size 0 0)
			(layers "B.Cu" "B.Mask" "B.Paste")
			(net "GND")
		)
	)
	(footprint ""
		(layer "B.Cu")
		(at 291.84981 -292.099746 90)
		(property "Reference" "C1715"
			(at 0 0 90)
			(layer "B.SilkS")
			(hide yes)
			(effects
				(font
					(size 1.27 1.27)
				)
				(justify mirror)
			)
		)
		(property "Value" ""
			(at 0 0 90)
			(layer "B.Fab")
			(effects
				(font
					(size 1.27 1.27)
				)
				(justify mirror)
			)
		)
		(duplicate_pad_numbers_are_jumpers no)
		(fp_line
			(start 0.299974 -0.150114)
			(end -0.299974 -0.150114)
			(stroke
				(width 0.1)
				(type default)
			)
			(layer "B.Fab")
		)
		(fp_line
			(start -0.299974 -0.150114)
			(end -0.299974 0.150114)
			(stroke
				(width 0.1)
				(type default)
			)
			(layer "B.Fab")
		)
		(fp_line
			(start 0.299974 0.150114)
			(end 0.299974 -0.150114)
			(stroke
				(width 0.1)
				(type default)
			)
			(layer "B.Fab")
		)
		(fp_line
			(start -0.299974 0.150114)
			(end 0.299974 0.150114)
			(stroke
				(width 0.1)
				(type default)
			)
			(layer "B.Fab")
		)
		(pad "1" smd rect
			(at 0.2667 0 270)
			(size 0.3048 0.381)
			(layers "B.Cu" "B.Mask" "B.Paste")
			(net "P0V8_SERDES_VDDA_PEX2")
		)
		(pad "2" smd rect
			(at -0.2667 0 270)
			(size 0.3048 0.381)
			(layers "B.Cu" "B.Mask" "B.Paste")
			(net "GND")
		)
	)
	(footprint ""
		(layer "B.Cu")
		(at 174.800006 -299.699934 -90)
		(property "Reference" "C1449"
			(at 0 0 90)
			(layer "B.SilkS")
			(hide yes)
			(effects
				(font
					(size 1.27 1.27)
				)
				(justify mirror)
			)
		)
		(property "Value" ""
			(at 0 0 90)
			(layer "B.Fab")
			(effects
				(font
					(size 1.27 1.27)
				)
				(justify mirror)
			)
		)
		(duplicate_pad_numbers_are_jumpers no)
		(fp_line
			(start -0.299974 0.150114)
			(end 0.299974 0.150114)
			(stroke
				(width 0.1)
				(type default)
			)
			(layer "B.Fab")
		)
		(fp_line
			(start 0.299974 0.150114)
			(end 0.299974 -0.150114)
			(stroke
				(width 0.1)
				(type default)
			)
			(layer "B.Fab")
		)
		(fp_line
			(start -0.299974 -0.150114)
			(end -0.299974 0.150114)
			(stroke
				(width 0.1)
				(type default)
			)
			(layer "B.Fab")
		)
		(fp_line
			(start 0.299974 -0.150114)
			(end -0.299974 -0.150114)
			(stroke
				(width 0.1)
				(type default)
			)
			(layer "B.Fab")
		)
		(pad "1" smd rect
			(at 0.2667 0 90)
			(size 0.3048 0.381)
			(layers "B.Cu" "B.Mask" "B.Paste")
			(net "P0V8_SERDES_VDDA_PEX1")
		)
		(pad "2" smd rect
			(at -0.2667 0 90)
			(size 0.3048 0.381)
			(layers "B.Cu" "B.Mask" "B.Paste")
			(net "GND")
		)
	)
	(footprint ""
		(layer "B.Cu")
		(at 301.349918 -297.32478 180)
		(property "Reference" "C1674"
			(at 0 0 0)
			(layer "B.SilkS")
			(hide yes)
			(effects
				(font
					(size 1.27 1.27)
				)
				(justify mirror)
			)
		)
		(property "Value" ""
			(at 0 0 0)
			(layer "B.Fab")
			(effects
				(font
					(size 1.27 1.27)
				)
				(justify mirror)
			)
		)
		(duplicate_pad_numbers_are_jumpers no)
		(fp_line
			(start 0.299974 0.150114)
			(end 0.299974 -0.150114)
			(stroke
				(width 0.1)
				(type default)
			)
			(layer "B.Fab")
		)
		(fp_line
			(start 0.299974 -0.150114)
			(end -0.299974 -0.150114)
			(stroke
				(width 0.1)
				(type default)
			)
			(layer "B.Fab")
		)
		(fp_line
			(start -0.299974 0.150114)
			(end 0.299974 0.150114)
			(stroke
				(width 0.1)
				(type default)
			)
			(layer "B.Fab")
		)
		(fp_line
			(start -0.299974 -0.150114)
			(end -0.299974 0.150114)
			(stroke
				(width 0.1)
				(type default)
			)
			(layer "B.Fab")
		)
		(pad "1" smd rect
			(at 0.2667 0)
			(size 0.3048 0.381)
			(layers "B.Cu" "B.Mask" "B.Paste")
			(net "P0V8_SERDES_VDDA_PEX2")
		)
		(pad "2" smd rect
			(at -0.2667 0)
			(size 0.3048 0.381)
			(layers "B.Cu" "B.Mask" "B.Paste")
			(net "GND")
		)
	)
	(footprint ""
		(layer "B.Cu")
		(at 77.541882 -104.120696 180)
		(property "Reference" "R66"
			(at 0 0 0)
			(layer "B.SilkS")
			(hide yes)
			(effects
				(font
					(size 1.27 1.27)
				)
				(justify mirror)
			)
		)
		(property "Value" ""
			(at 0 0 0)
			(layer "B.Fab")
			(effects
				(font
					(size 1.27 1.27)
				)
				(justify mirror)
			)
		)
		(duplicate_pad_numbers_are_jumpers no)
		(fp_line
			(start 0.7874 0.4064)
			(end 0.7874 -0.4064)
			(stroke
				(width 0.1524)
				(type default)
			)
			(layer "B.SilkS")
		)
		(fp_line
			(start 0.7874 -0.4064)
			(end -0.7874 -0.4064)
			(stroke
				(width 0.1524)
				(type default)
			)
			(layer "B.SilkS")
		)
		(fp_line
			(start -0.7874 0.4064)
			(end 0.7874 0.4064)
			(stroke
				(width 0.1524)
				(type default)
			)
			(layer "B.SilkS")
		)
		(fp_line
			(start -0.7874 -0.4064)
			(end -0.7874 0.4064)
			(stroke
				(width 0.1524)
				(type default)
			)
			(layer "B.SilkS")
		)
		(fp_line
			(start 0.67945 0.3048)
			(end 0.67945 -0.305054)
			(stroke
				(width 0.1)
				(type default)
			)
			(layer "B.Fab")
		)
		(fp_line
			(start 0.67945 -0.305054)
			(end 0.12065 -0.305054)
			(stroke
				(width 0.1)
				(type default)
			)
			(layer "B.Fab")
		)
		(fp_line
			(start 0.12065 0.3048)
			(end 0.67945 0.3048)
			(stroke
				(width 0.1)
				(type default)
			)
			(layer "B.Fab")
		)
		(fp_line
			(start 0.12065 0.2794)
			(end 0.12065 0.3048)
			(stroke
				(width 0.1)
				(type default)
			)
			(layer "B.Fab")
		)
		(fp_line
			(start 0.12065 -0.2794)
			(end -0.12065 -0.2794)
			(stroke
				(width 0.1)
				(type default)
			)
			(layer "B.Fab")
		)
		(fp_line
			(start 0.12065 -0.305054)
			(end 0.12065 -0.2794)
			(stroke
				(width 0.1)
				(type default)
			)
			(layer "B.Fab")
		)
		(fp_line
			(start -0.120396 0.3048)
			(end -0.120396 0.2794)
			(stroke
				(width 0.1)
				(type default)
			)
			(layer "B.Fab")
		)
		(fp_line
			(start -0.120396 0.2794)
			(end 0.12065 0.2794)
			(stroke
				(width 0.1)
				(type default)
			)
			(layer "B.Fab")
		)
		(fp_line
			(start -0.12065 -0.2794)
			(end -0.12065 -0.3048)
			(stroke
				(width 0.1)
				(type default)
			)
			(layer "B.Fab")
		)
		(fp_line
			(start -0.12065 -0.3048)
			(end -0.67945 -0.3048)
			(stroke
				(width 0.1)
				(type default)
			)
			(layer "B.Fab")
		)
		(fp_line
			(start -0.67945 0.3048)
			(end -0.120396 0.3048)
			(stroke
				(width 0.1)
				(type default)
			)
			(layer "B.Fab")
		)
		(fp_line
			(start -0.67945 -0.3048)
			(end -0.67945 0.3048)
			(stroke
				(width 0.1)
				(type default)
			)
			(layer "B.Fab")
		)
		(pad "1" smd circle
			(at 0.40005 0)
			(size 0 0)
			(layers "B.Cu" "B.Mask" "B.Paste")
			(net "NCSI_NIC1_CRS_DV")
		)
		(pad "2" smd circle
			(at -0.40005 0)
			(size 0 0)
			(layers "B.Cu" "B.Mask" "B.Paste")
			(net "GND")
		)
	)
	(footprint ""
		(layer "B.Cu")
		(at 55.30215 -158.343092)
		(property "Reference" "C858"
			(at 0 0 0)
			(layer "B.SilkS")
			(hide yes)
			(effects
				(font
					(size 1.27 1.27)
				)
				(justify mirror)
			)
		)
		(property "Value" ""
			(at 0 0 0)
			(layer "B.Fab")
			(effects
				(font
					(size 1.27 1.27)
				)
				(justify mirror)
			)
		)
		(duplicate_pad_numbers_are_jumpers no)
		(fp_line
			(start -0.7874 -0.4064)
			(end -0.7874 0.4064)
			(stroke
				(width 0.1524)
				(type default)
			)
			(layer "B.SilkS")
		)
		(fp_line
			(start -0.7874 0.4064)
			(end 0.7874 0.4064)
			(stroke
				(width 0.1524)
				(type default)
			)
			(layer "B.SilkS")
		)
		(fp_line
			(start 0.7874 -0.4064)
			(end -0.7874 -0.4064)
			(stroke
				(width 0.1524)
				(type default)
			)
			(layer "B.SilkS")
		)
		(fp_line
			(start 0.7874 0.4064)
			(end 0.7874 -0.4064)
			(stroke
				(width 0.1524)
				(type default)
			)
			(layer "B.SilkS")
		)
		(fp_line
			(start -0.67945 -0.3048)
			(end -0.67945 0.3048)
			(stroke
				(width 0.1)
				(type default)
			)
			(layer "B.Fab")
		)
		(fp_line
			(start -0.67945 0.3048)
			(end -0.120396 0.3048)
			(stroke
				(width 0.1)
				(type default)
			)
			(layer "B.Fab")
		)
		(fp_line
			(start -0.12065 -0.3048)
			(end -0.67945 -0.3048)
			(stroke
				(width 0.1)
				(type default)
			)
			(layer "B.Fab")
		)
		(fp_line
			(start -0.12065 -0.2794)
			(end -0.12065 -0.3048)
			(stroke
				(width 0.1)
				(type default)
			)
			(layer "B.Fab")
		)
		(fp_line
			(start -0.120396 0.2794)
			(end 0.12065 0.2794)
			(stroke
				(width 0.1)
				(type default)
			)
			(layer "B.Fab")
		)
		(fp_line
			(start -0.120396 0.3048)
			(end -0.120396 0.2794)
			(stroke
				(width 0.1)
				(type default)
			)
			(layer "B.Fab")
		)
		(fp_line
			(start 0.12065 -0.305054)
			(end 0.12065 -0.2794)
			(stroke
				(width 0.1)
				(type default)
			)
			(layer "B.Fab")
		)
		(fp_line
			(start 0.12065 -0.2794)
			(end -0.12065 -0.2794)
			(stroke
				(width 0.1)
				(type default)
			)
			(layer "B.Fab")
		)
		(fp_line
			(start 0.12065 0.2794)
			(end 0.12065 0.3048)
			(stroke
				(width 0.1)
				(type default)
			)
			(layer "B.Fab")
		)
		(fp_line
			(start 0.12065 0.3048)
			(end 0.67945 0.3048)
			(stroke
				(width 0.1)
				(type default)
			)
			(layer "B.Fab")
		)
		(fp_line
			(start 0.67945 -0.305054)
			(end 0.12065 -0.305054)
			(stroke
				(width 0.1)
				(type default)
			)
			(layer "B.Fab")
		)
		(fp_line
			(start 0.67945 0.3048)
			(end 0.67945 -0.305054)
			(stroke
				(width 0.1)
				(type default)
			)
			(layer "B.Fab")
		)
		(pad "1" smd circle
			(at 0.40005 0 180)
			(size 0 0)
			(layers "B.Cu" "B.Mask" "B.Paste")
			(net "P3V3_AUX")
		)
		(pad "2" smd circle
			(at -0.40005 0 180)
			(size 0 0)
			(layers "B.Cu" "B.Mask" "B.Paste")
			(net "GND")
		)
	)
)
